#ISCELL
  mstr_misc dns *
  *
#ISCELL
  pure_quanta quanta_title_block_c *
  *
#ISCELL
  pure_quanta_power universal_gnd *
  page187_i1
#ISCELL
  standard offpage *
  page187_i101
#ISCELL
  pure_quanta_power universal_gnd *
  page187_i102
#ISCELL
  standard offpage *
  page187_i103
#ISCELL
  standard offpage *
  page187_i104
#CELL
  pure_quanta q_cap *
  page187_i105
#ISCELL
  pure_quanta_power universal_gnd *
  page187_i106
#CELL
  pure_quanta q_cap *
  page187_i107
#CELL
  pure_quanta q_cap *
  page187_i108
#CELL
  pure_quanta q_cap *
  page187_i109
#ISCELL
  pure_quanta_power universal_gnd *
  page187_i110
#ISCELL
  pure_quanta_power universal_gnd *
  page187_i111
#CELL
  pure_quanta q_res *
  page187_i112
#CELL
  pure_quanta q_cap *
  page187_i113
#ISCELL
  pure_quanta_power vcc_core *
  page187_i114
#CELL
  pure_quanta q_cap *
  page187_i115
#ISCELL
  pure_quanta_power universal_gnd *
  page187_i116
#ISCELL
  pure_quanta_power universal_gnd *
  page187_i117
#CELL
  pure_quanta q_res *
  page187_i118
#CELL
  pure_quanta q_cap *
  page187_i119
#ISCELL
  pure_quanta_power vcc_core *
  page187_i120
#ISCELL
  pure_quanta_power universal_gnd *
  page187_i121
#CELL
  pure_quanta q_res *
  page187_i122
#CELL
  pure_quanta q_cap *
  page187_i123
#ISCELL
  pure_quanta_power universal_gnd *
  page187_i124
#CELL
  pure_quanta q_res *
  page187_i125
#CELL
  pure_quanta q_cap *
  page187_i126
#ISCELL
  pure_quanta_power universal_gnd *
  page187_i127
#ISCELL
  pure_quanta_power universal_gnd *
  page187_i15
#CELL
  pure_quanta q_res *
  page187_i16
#CELL
  pure_quanta q_res *
  page187_i18
#CELL
  pure_quanta q_cap *
  page187_i19
#ISCELL
  standard offpage *
  page187_i2
#CELL
  pure_quanta q_cap *
  page187_i20
#CELL
  pure_quanta q_cap *
  page187_i21
#ISCELL
  standard offpage *
  page187_i22
#CELL
  pure_quanta q_inductor4p_14 *
  page187_i23
#CELL
  pure_quanta q_cap *
  page187_i26
#ISCELL
  pure_quanta_power universal_gnd *
  page187_i27
#CELL
  pure_quanta q_cap *
  page187_i28
#ISCELL
  pure_quanta_power vcc_core *
  page187_i29
#CELL
  pure_quanta q_cap *
  page187_i3
#CELL
  pure_quanta q_cap *
  page187_i31
#ISCELL
  pure_quanta_power universal_gnd *
  page187_i32
#CELL
  pure_quanta q_cap *
  page187_i33
#ISCELL
  pure_quanta_power vcc_core *
  page187_i34
#CELL
  pure_quanta isl99390frztr5935 *
  page187_i35
#ISCELL
  pure_quanta_power universal_gnd *
  page187_i4
#ISCELL
  standard offpage *
  page187_i5
#ISCELL
  standard offpage *
  page187_i6
#ISCELL
  standard offpage *
  page187_i7
#ISCELL
  standard offpage *
  page187_i71
#CELL
  pure_quanta isl99390frztr5935 *
  page187_i72
#ISCELL
  standard offpage *
  page187_i73
#ISCELL
  pure_quanta_power vcc_core *
  page187_i74
#CELL
  pure_quanta q_cap *
  page187_i75
#ISCELL
  pure_quanta_power universal_gnd *
  page187_i76
#CELL
  pure_quanta q_cap *
  page187_i77
#CELL
  pure_quanta q_res *
  page187_i8
#ISCELL
  pure_quanta_power vcc_core *
  page187_i81
#CELL
  pure_quanta q_cap *
  page187_i82
#ISCELL
  pure_quanta_power universal_gnd *
  page187_i83
#CELL
  pure_quanta q_inductor4p_14 *
  page187_i84
#CELL
  pure_quanta q_cap *
  page187_i85
#CELL
  pure_quanta q_cap *
  page187_i86
#CELL
  pure_quanta q_cap *
  page187_i87
#CELL
  pure_quanta q_cap *
  page187_i88
#CELL
  pure_quanta q_res *
  page187_i89
#CELL
  pure_quanta q_res *
  page187_i90
#ISCELL
  pure_quanta_power universal_gnd *
  page187_i92
#CELL
  pure_quanta q_res *
  page187_i96
#ISCELL
  standard offpage *
  page187_i99
